(kicad_pcb
	(version 20260206)
	(generator "pcbnew")
	(generator_version "10.0")
	(general
		(thickness 1.6)
		(legacy_teardrops no)
	)
	(paper "A4")
	(title_block
		(title "panther-plus-userver — 13130-1b_20150205.brd")
		(comment 1 "Honey Badger (Wiwynn) / footprint 624 of 1509 (DIMM4), pads 142-148 of 210")
	)
	(layers
		(0 "F.Cu" signal "TOP")
		(4 "In1.Cu" signal "L2")
		(6 "In2.Cu" signal "L3")
		(8 "In3.Cu" signal "L4")
		(10 "In4.Cu" signal "L5")
		(12 "In5.Cu" signal "L6")
		(14 "In6.Cu" signal "L7")
		(16 "In7.Cu" signal "L8")
		(18 "In8.Cu" signal "L9")
		(20 "In9.Cu" signal "L10")
		(22 "In10.Cu" signal "L11")
		(2 "B.Cu" signal "BOTTOM")
		(9 "F.Adhes" user "F.Adhesive")
		(11 "B.Adhes" user "B.Adhesive")
		(13 "F.Paste" user "Package Geometry/Pastemask Top")
		(15 "B.Paste" user "Package Geometry/Pastemask Bottom")
		(5 "F.SilkS" user "Ref Des/Silkscreen Top")
		(7 "B.SilkS" user "Ref Des/Silkscreen Bottom")
		(1 "F.Mask" user "Board Geometry/Soldermask Top")
		(3 "B.Mask" user "Board Geometry/Soldermask Bottom")
		(17 "Dwgs.User" user "User.Drawings")
		(19 "Cmts.User" user "User.Comments")
		(21 "Eco1.User" user "User.Eco1")
		(23 "Eco2.User" user "User.Eco2")
		(25 "Edge.Cuts" user "Board Geometry/Outline")
		(27 "Margin" user)
		(31 "F.CrtYd" user "Package Geometry/Place Bound Top")
		(29 "B.CrtYd" user "Package Geometry/Place Bound Bottom")
		(35 "F.Fab" user "Ref Des/Assembly Top")
		(33 "B.Fab" user "Ref Des/Assembly Bottom")
	)
	(footprint ""
		(layer "F.Cu")
		(at 159.999934 -5.790692)
		(property "Reference" "DIMM4"
			(at 0 0 0)
			(layer "F.SilkS")
			(hide yes)
			(effects
				(font
					(size 1.27 1.27)
				)
			)
		)
		(property "Value" "DDR3-204P-174-COLAY-1-GP"
			(at -40.682164 -17.468088 0)
			(unlocked yes)
			(layer "F.Fab")
			(hide yes)
			(effects
				(font
					(size 1.016 1.016)
					(thickness 0.1524)
				)
			)
		)
		(property "Device Type" "AS0A626-H8SN-7H-COLAY-1"
			(at -40.682164 -18.992088 0)
			(unlocked yes)
			(layer "F.Fab")
			(hide yes)
			(effects
				(font
					(size 1.016 1.016)
					(thickness 0.1524)
				)
			)
		)
		(duplicate_pad_numbers_are_jumpers no)
		(pad "140" smd custom
			(at 12.450064 -4.106672)
			(size 0.1143 0.1143)
			(layers "F.Cu" "F.Mask" "F.Paste")
			(net "GND")
			(options
				(clearance outline)
				(anchor circle)
			)
			(primitives
				(gr_poly
					(pts
						(xy 0 0.9017) (xy -0.03175 0.89916) (xy -0.0635 0.889) (xy -0.09144 0.87376) (xy -0.11684 0.85344)
						(xy -0.13716 0.82804) (xy -0.1524 0.8001) (xy -0.16256 0.76835) (xy -0.1651 0.7366) (xy -0.1651 0.19685)
						(xy -0.17272 0.18923) (xy -0.17907 0.18034) (xy -0.18669 0.17145) (xy -0.19177 0.16256) (xy -0.19812 0.15367)
						(xy -0.20828 0.13335) (xy -0.21971 0.10287) (xy -0.22225 0.09271) (xy -0.22479 0.08128) (xy -0.22606 0.07112)
						(xy -0.2286 0.05969) (xy -0.2286 0.01651) (xy -0.22606 0.00508) (xy -0.22479 -0.00508) (xy -0.22225 -0.01651)
						(xy -0.21971 -0.02667) (xy -0.20828 -0.05715) (xy -0.19812 -0.07747) (xy -0.19177 -0.08636) (xy -0.18669 -0.09525)
						(xy -0.17907 -0.10414) (xy -0.17272 -0.11303) (xy -0.1651 -0.12065) (xy -0.1651 -0.7366) (xy -0.16256 -0.76835)
						(xy -0.1524 -0.8001) (xy -0.13716 -0.82804) (xy -0.11684 -0.85344) (xy -0.09144 -0.87376) (xy -0.0635 -0.889)
						(xy -0.03175 -0.89916) (xy 0 -0.9017) (xy 0.03175 -0.89916) (xy 0.0635 -0.889) (xy 0.09144 -0.87376)
						(xy 0.11684 -0.85344) (xy 0.13716 -0.82804) (xy 0.1524 -0.8001) (xy 0.16256 -0.76835) (xy 0.1651 -0.7366)
						(xy 0.1651 -0.11938) (xy 0.17272 -0.11176) (xy 0.19812 -0.0762) (xy 0.2032 -0.06604) (xy 0.20701 -0.05715)
						(xy 0.21209 -0.04699) (xy 0.2159 -0.03683) (xy 0.21844 -0.02667) (xy 0.22225 -0.01524) (xy 0.22352 -0.00508)
						(xy 0.22606 0.00508) (xy 0.22733 0.01651) (xy 0.22733 0.02667) (xy 0.2286 0.0381) (xy 0.22733 0.04953)
						(xy 0.22733 0.05969) (xy 0.22606 0.07112) (xy 0.22352 0.08128) (xy 0.22225 0.09144) (xy 0.21844 0.10287)
						(xy 0.2159 0.11303) (xy 0.21209 0.12319) (xy 0.20701 0.13335) (xy 0.2032 0.14224) (xy 0.19812 0.1524)
						(xy 0.17272 0.18796) (xy 0.1651 0.19558) (xy 0.1651 0.7366) (xy 0.16256 0.76835) (xy 0.1524 0.8001)
						(xy 0.13716 0.82804) (xy 0.11684 0.85344) (xy 0.09144 0.87376) (xy 0.0635 0.889) (xy 0.03175 0.89916)
					)
					(width 0)
					(fill yes)
				)
			)
		)
		(pad "141" smd custom
			(at 12.750038 4.106672)
			(size 0.1143 0.1143)
			(layers "F.Cu" "F.Mask" "F.Paste")
			(net "M_B_DQS_DP4")
			(options
				(clearance outline)
				(anchor circle)
			)
			(primitives
				(gr_poly
					(pts
						(xy 0 0.9017) (xy -0.03175 0.89916) (xy -0.0635 0.889) (xy -0.09144 0.87376) (xy -0.11684 0.85344)
						(xy -0.13716 0.82804) (xy -0.1524 0.8001) (xy -0.16256 0.76835) (xy -0.1651 0.7366) (xy -0.1651 -0.13462)
						(xy -0.17272 -0.14224) (xy -0.19812 -0.1778) (xy -0.2032 -0.18796) (xy -0.20701 -0.19685) (xy -0.21209 -0.20701)
						(xy -0.2159 -0.21717) (xy -0.21844 -0.22733) (xy -0.22225 -0.23876) (xy -0.22352 -0.24892) (xy -0.22606 -0.25908)
						(xy -0.22733 -0.27051) (xy -0.22733 -0.28067) (xy -0.2286 -0.2921) (xy -0.22733 -0.30353) (xy -0.22733 -0.31369)
						(xy -0.22606 -0.32512) (xy -0.22352 -0.33528) (xy -0.22225 -0.34544) (xy -0.21844 -0.35687) (xy -0.2159 -0.36703)
						(xy -0.21209 -0.37719) (xy -0.20701 -0.38735) (xy -0.2032 -0.39624) (xy -0.19812 -0.4064) (xy -0.17272 -0.44196)
						(xy -0.1651 -0.44958) (xy -0.1651 -0.7366) (xy -0.16256 -0.76835) (xy -0.1524 -0.8001) (xy -0.13716 -0.82804)
						(xy -0.11684 -0.85344) (xy -0.09144 -0.87376) (xy -0.0635 -0.889) (xy -0.03175 -0.89916) (xy 0 -0.9017)
						(xy 0.03175 -0.89916) (xy 0.0635 -0.889) (xy 0.09144 -0.87376) (xy 0.11684 -0.85344) (xy 0.13716 -0.82804)
						(xy 0.1524 -0.8001) (xy 0.16256 -0.76835) (xy 0.1651 -0.7366) (xy 0.1651 -0.44958) (xy 0.17272 -0.44196)
						(xy 0.19812 -0.4064) (xy 0.2032 -0.39624) (xy 0.20701 -0.38735) (xy 0.21209 -0.37719) (xy 0.2159 -0.36703)
						(xy 0.21844 -0.35687) (xy 0.22225 -0.34544) (xy 0.22352 -0.33528) (xy 0.22606 -0.32512) (xy 0.22733 -0.31369)
						(xy 0.22733 -0.30353) (xy 0.2286 -0.2921) (xy 0.22733 -0.28067) (xy 0.22733 -0.27051) (xy 0.22606 -0.25908)
						(xy 0.22352 -0.24892) (xy 0.22225 -0.23876) (xy 0.21844 -0.22733) (xy 0.2159 -0.21717) (xy 0.21209 -0.20701)
						(xy 0.20701 -0.19685) (xy 0.2032 -0.18796) (xy 0.19812 -0.1778) (xy 0.17272 -0.14224) (xy 0.1651 -0.13462)
						(xy 0.1651 0.7366) (xy 0.16256 0.76835) (xy 0.1524 0.8001) (xy 0.13716 0.82804) (xy 0.11684 0.85344)
						(xy 0.09144 0.87376) (xy 0.0635 0.889) (xy 0.03175 0.89916)
					)
					(width 0)
					(fill yes)
				)
			)
		)
		(pad "142" smd custom
			(at 13.050012 -4.106672)
			(size 0.1143 0.1143)
			(layers "F.Cu" "F.Mask" "F.Paste")
			(net "M_B_DQ34")
			(options
				(clearance outline)
				(anchor circle)
			)
			(primitives
				(gr_poly
					(pts
						(xy 0 0.9017) (xy -0.03175 0.89916) (xy -0.0635 0.889) (xy -0.09144 0.87376) (xy -0.11684 0.85344)
						(xy -0.13716 0.82804) (xy -0.1524 0.8001) (xy -0.16256 0.76835) (xy -0.1651 0.7366) (xy -0.1651 0.44958)
						(xy -0.17272 0.44196) (xy -0.19812 0.4064) (xy -0.2032 0.39624) (xy -0.20701 0.38735) (xy -0.21209 0.37719)
						(xy -0.2159 0.36703) (xy -0.21844 0.35687) (xy -0.22225 0.34544) (xy -0.22352 0.33528) (xy -0.22606 0.32512)
						(xy -0.22733 0.31369) (xy -0.22733 0.30353) (xy -0.2286 0.2921) (xy -0.22733 0.28067) (xy -0.22733 0.27051)
						(xy -0.22606 0.25908) (xy -0.22352 0.24892) (xy -0.22225 0.23876) (xy -0.21844 0.22733) (xy -0.2159 0.21717)
						(xy -0.21209 0.20701) (xy -0.20701 0.19685) (xy -0.2032 0.18796) (xy -0.19812 0.1778) (xy -0.17272 0.14224)
						(xy -0.1651 0.13462) (xy -0.1651 -0.7366) (xy -0.16256 -0.76835) (xy -0.1524 -0.8001) (xy -0.13716 -0.82804)
						(xy -0.11684 -0.85344) (xy -0.09144 -0.87376) (xy -0.0635 -0.889) (xy -0.03175 -0.89916) (xy 0 -0.9017)
						(xy 0.03175 -0.89916) (xy 0.0635 -0.889) (xy 0.09144 -0.87376) (xy 0.11684 -0.85344) (xy 0.13716 -0.82804)
						(xy 0.1524 -0.8001) (xy 0.16256 -0.76835) (xy 0.1651 -0.7366) (xy 0.1651 0.13462) (xy 0.17272 0.14224)
						(xy 0.19812 0.1778) (xy 0.2032 0.18796) (xy 0.20701 0.19685) (xy 0.21209 0.20701) (xy 0.2159 0.21717)
						(xy 0.21844 0.22733) (xy 0.22225 0.23876) (xy 0.22352 0.24892) (xy 0.22606 0.25908) (xy 0.22733 0.27051)
						(xy 0.22733 0.28067) (xy 0.2286 0.2921) (xy 0.22733 0.30353) (xy 0.22733 0.31369) (xy 0.22606 0.32512)
						(xy 0.22352 0.33528) (xy 0.22225 0.34544) (xy 0.21844 0.35687) (xy 0.2159 0.36703) (xy 0.21209 0.37719)
						(xy 0.20701 0.38735) (xy 0.2032 0.39624) (xy 0.19812 0.4064) (xy 0.17272 0.44196) (xy 0.1651 0.44958)
						(xy 0.1651 0.7366) (xy 0.16256 0.76835) (xy 0.1524 0.8001) (xy 0.13716 0.82804) (xy 0.11684 0.85344)
						(xy 0.09144 0.87376) (xy 0.0635 0.889) (xy 0.03175 0.89916)
					)
					(width 0)
					(fill yes)
				)
			)
		)
		(pad "143" smd custom
			(at 13.349986 4.106672)
			(size 0.1143 0.1143)
			(layers "F.Cu" "F.Mask" "F.Paste")
			(net "GND")
			(options
				(clearance outline)
				(anchor circle)
			)
			(primitives
				(gr_poly
					(pts
						(xy 0 0.9017) (xy -0.03175 0.89916) (xy -0.0635 0.889) (xy -0.09144 0.87376) (xy -0.11684 0.85344)
						(xy -0.13716 0.82804) (xy -0.1524 0.8001) (xy -0.16256 0.76835) (xy -0.1651 0.7366) (xy -0.1651 0.11938)
						(xy -0.17272 0.11176) (xy -0.19812 0.0762) (xy -0.2032 0.06604) (xy -0.20701 0.05715) (xy -0.21209 0.04699)
						(xy -0.2159 0.03683) (xy -0.21844 0.02667) (xy -0.22225 0.01524) (xy -0.22352 0.00508) (xy -0.22606 -0.00508)
						(xy -0.22733 -0.01651) (xy -0.22733 -0.02667) (xy -0.2286 -0.0381) (xy -0.22733 -0.04953) (xy -0.22733 -0.05969)
						(xy -0.22606 -0.07112) (xy -0.22352 -0.08128) (xy -0.22225 -0.09144) (xy -0.21844 -0.10287) (xy -0.2159 -0.11303)
						(xy -0.21209 -0.12319) (xy -0.20701 -0.13335) (xy -0.2032 -0.14224) (xy -0.19812 -0.1524) (xy -0.17272 -0.18796)
						(xy -0.1651 -0.19558) (xy -0.1651 -0.7366) (xy -0.16256 -0.76835) (xy -0.1524 -0.8001) (xy -0.13716 -0.82804)
						(xy -0.11684 -0.85344) (xy -0.09144 -0.87376) (xy -0.0635 -0.889) (xy -0.03175 -0.89916) (xy 0 -0.9017)
						(xy 0.03175 -0.89916) (xy 0.0635 -0.889) (xy 0.09144 -0.87376) (xy 0.11684 -0.85344) (xy 0.13716 -0.82804)
						(xy 0.1524 -0.8001) (xy 0.16256 -0.76835) (xy 0.1651 -0.7366) (xy 0.1651 -0.19685) (xy 0.17272 -0.18923)
						(xy 0.17907 -0.18034) (xy 0.18669 -0.17145) (xy 0.19177 -0.16256) (xy 0.19812 -0.15367) (xy 0.20828 -0.13335)
						(xy 0.21971 -0.10287) (xy 0.22225 -0.09271) (xy 0.22479 -0.08128) (xy 0.22606 -0.07112) (xy 0.2286 -0.05969)
						(xy 0.2286 -0.01651) (xy 0.22606 -0.00508) (xy 0.22479 0.00508) (xy 0.22225 0.01651) (xy 0.21971 0.02667)
						(xy 0.20828 0.05715) (xy 0.19812 0.07747) (xy 0.19177 0.08636) (xy 0.18669 0.09525) (xy 0.17907 0.10414)
						(xy 0.17272 0.11303) (xy 0.1651 0.12065) (xy 0.1651 0.7366) (xy 0.16256 0.76835) (xy 0.1524 0.8001)
						(xy 0.13716 0.82804) (xy 0.11684 0.85344) (xy 0.09144 0.87376) (xy 0.0635 0.889) (xy 0.03175 0.89916)
					)
					(width 0)
					(fill yes)
				)
			)
		)
		(pad "144" smd custom
			(at 13.64996 -4.106672)
			(size 0.1143 0.1143)
			(layers "F.Cu" "F.Mask" "F.Paste")
			(net "M_B_DQ35")
			(options
				(clearance outline)
				(anchor circle)
			)
			(primitives
				(gr_poly
					(pts
						(xy 0 0.9017) (xy -0.03175 0.89916) (xy -0.0635 0.889) (xy -0.09144 0.87376) (xy -0.11684 0.85344)
						(xy -0.13716 0.82804) (xy -0.1524 0.8001) (xy -0.16256 0.76835) (xy -0.1651 0.7366) (xy -0.1651 0.19685)
						(xy -0.17272 0.18923) (xy -0.17907 0.18034) (xy -0.18669 0.17145) (xy -0.19177 0.16256) (xy -0.19812 0.15367)
						(xy -0.20828 0.13335) (xy -0.21971 0.10287) (xy -0.22225 0.09271) (xy -0.22479 0.08128) (xy -0.22606 0.07112)
						(xy -0.2286 0.05969) (xy -0.2286 0.01651) (xy -0.22606 0.00508) (xy -0.22479 -0.00508) (xy -0.22225 -0.01651)
						(xy -0.21971 -0.02667) (xy -0.20828 -0.05715) (xy -0.19812 -0.07747) (xy -0.19177 -0.08636) (xy -0.18669 -0.09525)
						(xy -0.17907 -0.10414) (xy -0.17272 -0.11303) (xy -0.1651 -0.12065) (xy -0.1651 -0.7366) (xy -0.16256 -0.76835)
						(xy -0.1524 -0.8001) (xy -0.13716 -0.82804) (xy -0.11684 -0.85344) (xy -0.09144 -0.87376) (xy -0.0635 -0.889)
						(xy -0.03175 -0.89916) (xy 0 -0.9017) (xy 0.03175 -0.89916) (xy 0.0635 -0.889) (xy 0.09144 -0.87376)
						(xy 0.11684 -0.85344) (xy 0.13716 -0.82804) (xy 0.1524 -0.8001) (xy 0.16256 -0.76835) (xy 0.1651 -0.7366)
						(xy 0.1651 -0.11938) (xy 0.17272 -0.11176) (xy 0.19812 -0.0762) (xy 0.2032 -0.06604) (xy 0.20701 -0.05715)
						(xy 0.21209 -0.04699) (xy 0.2159 -0.03683) (xy 0.21844 -0.02667) (xy 0.22225 -0.01524) (xy 0.22352 -0.00508)
						(xy 0.22606 0.00508) (xy 0.22733 0.01651) (xy 0.22733 0.02667) (xy 0.2286 0.0381) (xy 0.22733 0.04953)
						(xy 0.22733 0.05969) (xy 0.22606 0.07112) (xy 0.22352 0.08128) (xy 0.22225 0.09144) (xy 0.21844 0.10287)
						(xy 0.2159 0.11303) (xy 0.21209 0.12319) (xy 0.20701 0.13335) (xy 0.2032 0.14224) (xy 0.19812 0.1524)
						(xy 0.17272 0.18796) (xy 0.1651 0.19558) (xy 0.1651 0.7366) (xy 0.16256 0.76835) (xy 0.1524 0.8001)
						(xy 0.13716 0.82804) (xy 0.11684 0.85344) (xy 0.09144 0.87376) (xy 0.0635 0.889) (xy 0.03175 0.89916)
					)
					(width 0)
					(fill yes)
				)
			)
		)
		(pad "145" smd custom
			(at 13.949934 4.106672)
			(size 0.1143 0.1143)
			(layers "F.Cu" "F.Mask" "F.Paste")
			(net "M_B_DQ38")
			(options
				(clearance outline)
				(anchor circle)
			)
			(primitives
				(gr_poly
					(pts
						(xy 0 0.9017) (xy -0.03175 0.89916) (xy -0.0635 0.889) (xy -0.09144 0.87376) (xy -0.11684 0.85344)
						(xy -0.13716 0.82804) (xy -0.1524 0.8001) (xy -0.16256 0.76835) (xy -0.1651 0.7366) (xy -0.1651 -0.13462)
						(xy -0.17272 -0.14224) (xy -0.19812 -0.1778) (xy -0.2032 -0.18796) (xy -0.20701 -0.19685) (xy -0.21209 -0.20701)
						(xy -0.2159 -0.21717) (xy -0.21844 -0.22733) (xy -0.22225 -0.23876) (xy -0.22352 -0.24892) (xy -0.22606 -0.25908)
						(xy -0.22733 -0.27051) (xy -0.22733 -0.28067) (xy -0.2286 -0.2921) (xy -0.22733 -0.30353) (xy -0.22733 -0.31369)
						(xy -0.22606 -0.32512) (xy -0.22352 -0.33528) (xy -0.22225 -0.34544) (xy -0.21844 -0.35687) (xy -0.2159 -0.36703)
						(xy -0.21209 -0.37719) (xy -0.20701 -0.38735) (xy -0.2032 -0.39624) (xy -0.19812 -0.4064) (xy -0.17272 -0.44196)
						(xy -0.1651 -0.44958) (xy -0.1651 -0.7366) (xy -0.16256 -0.76835) (xy -0.1524 -0.8001) (xy -0.13716 -0.82804)
						(xy -0.11684 -0.85344) (xy -0.09144 -0.87376) (xy -0.0635 -0.889) (xy -0.03175 -0.89916) (xy 0 -0.9017)
						(xy 0.03175 -0.89916) (xy 0.0635 -0.889) (xy 0.09144 -0.87376) (xy 0.11684 -0.85344) (xy 0.13716 -0.82804)
						(xy 0.1524 -0.8001) (xy 0.16256 -0.76835) (xy 0.1651 -0.7366) (xy 0.1651 -0.44958) (xy 0.17272 -0.44196)
						(xy 0.19812 -0.4064) (xy 0.2032 -0.39624) (xy 0.20701 -0.38735) (xy 0.21209 -0.37719) (xy 0.2159 -0.36703)
						(xy 0.21844 -0.35687) (xy 0.22225 -0.34544) (xy 0.22352 -0.33528) (xy 0.22606 -0.32512) (xy 0.22733 -0.31369)
						(xy 0.22733 -0.30353) (xy 0.2286 -0.2921) (xy 0.22733 -0.28067) (xy 0.22733 -0.27051) (xy 0.22606 -0.25908)
						(xy 0.22352 -0.24892) (xy 0.22225 -0.23876) (xy 0.21844 -0.22733) (xy 0.2159 -0.21717) (xy 0.21209 -0.20701)
						(xy 0.20701 -0.19685) (xy 0.2032 -0.18796) (xy 0.19812 -0.1778) (xy 0.17272 -0.14224) (xy 0.1651 -0.13462)
						(xy 0.1651 0.7366) (xy 0.16256 0.76835) (xy 0.1524 0.8001) (xy 0.13716 0.82804) (xy 0.11684 0.85344)
						(xy 0.09144 0.87376) (xy 0.0635 0.889) (xy 0.03175 0.89916)
					)
					(width 0)
					(fill yes)
				)
			)
		)
		(pad "146" smd custom
			(at 14.249908 -4.106672)
			(size 0.1143 0.1143)
			(layers "F.Cu" "F.Mask" "F.Paste")
			(net "GND")
			(options
				(clearance outline)
				(anchor circle)
			)
			(primitives
				(gr_poly
					(pts
						(xy 0 0.9017) (xy -0.03175 0.89916) (xy -0.0635 0.889) (xy -0.09144 0.87376) (xy -0.11684 0.85344)
						(xy -0.13716 0.82804) (xy -0.1524 0.8001) (xy -0.16256 0.76835) (xy -0.1651 0.7366) (xy -0.1651 0.44958)
						(xy -0.17272 0.44196) (xy -0.19812 0.4064) (xy -0.2032 0.39624) (xy -0.20701 0.38735) (xy -0.21209 0.37719)
						(xy -0.2159 0.36703) (xy -0.21844 0.35687) (xy -0.22225 0.34544) (xy -0.22352 0.33528) (xy -0.22606 0.32512)
						(xy -0.22733 0.31369) (xy -0.22733 0.30353) (xy -0.2286 0.2921) (xy -0.22733 0.28067) (xy -0.22733 0.27051)
						(xy -0.22606 0.25908) (xy -0.22352 0.24892) (xy -0.22225 0.23876) (xy -0.21844 0.22733) (xy -0.2159 0.21717)
						(xy -0.21209 0.20701) (xy -0.20701 0.19685) (xy -0.2032 0.18796) (xy -0.19812 0.1778) (xy -0.17272 0.14224)
						(xy -0.1651 0.13462) (xy -0.1651 -0.7366) (xy -0.16256 -0.76835) (xy -0.1524 -0.8001) (xy -0.13716 -0.82804)
						(xy -0.11684 -0.85344) (xy -0.09144 -0.87376) (xy -0.0635 -0.889) (xy -0.03175 -0.89916) (xy 0 -0.9017)
						(xy 0.03175 -0.89916) (xy 0.0635 -0.889) (xy 0.09144 -0.87376) (xy 0.11684 -0.85344) (xy 0.13716 -0.82804)
						(xy 0.1524 -0.8001) (xy 0.16256 -0.76835) (xy 0.1651 -0.7366) (xy 0.1651 0.13462) (xy 0.17272 0.14224)
						(xy 0.19812 0.1778) (xy 0.2032 0.18796) (xy 0.20701 0.19685) (xy 0.21209 0.20701) (xy 0.2159 0.21717)
						(xy 0.21844 0.22733) (xy 0.22225 0.23876) (xy 0.22352 0.24892) (xy 0.22606 0.25908) (xy 0.22733 0.27051)
						(xy 0.22733 0.28067) (xy 0.2286 0.2921) (xy 0.22733 0.30353) (xy 0.22733 0.31369) (xy 0.22606 0.32512)
						(xy 0.22352 0.33528) (xy 0.22225 0.34544) (xy 0.21844 0.35687) (xy 0.2159 0.36703) (xy 0.21209 0.37719)
						(xy 0.20701 0.38735) (xy 0.2032 0.39624) (xy 0.19812 0.4064) (xy 0.17272 0.44196) (xy 0.1651 0.44958)
						(xy 0.1651 0.7366) (xy 0.16256 0.76835) (xy 0.1524 0.8001) (xy 0.13716 0.82804) (xy 0.11684 0.85344)
						(xy 0.09144 0.87376) (xy 0.0635 0.889) (xy 0.03175 0.89916)
					)
					(width 0)
					(fill yes)
				)
			)
		)
	)
)
